# T6G (Grand Teton) — schematic netlist excerpt (pin names and nets, part order shuffled) for the footprints in the layout excerpt that follows; sources: Cadence DE-HDL packaged netlist, KiCad conversion of 04192023_DAF0TMB3IC0_F0TG_MB_C_brd_V02_OCP.brd

R1184  Q_RES  1K 1% CHIP  pkg 0402LF  page 104 : A = PWRGD_CHG_CPU1_DIMM0 ; B = PWRGD_CHGL_CPU1
C6108  Q_CAP  0.1UF 25V 10% X7R  pkg 0402  page 179 : A = P1V2_CPU0_USB2_DVDD12 ; B = GND

(kicad_pcb
	(version 20260206)
	(generator "pcbnew")
	(generator_version "10.0")
	(general
		(thickness 1.6)
		(legacy_teardrops no)
	)
	(paper "A4")
	(title_block
		(title "04192023_DAF0TMB3IC0_F0TG_MB_C_brd_V02_OCP.brd")
		(comment 1 "Grand Teton / footprints 8255-8256 of 8354")
	)
	(layers
		(0 "F.Cu" signal "TOP")
		(4 "In1.Cu" signal "GND")
		(6 "In2.Cu" signal "IN1")
		(8 "In3.Cu" signal "GND1")
		(10 "In4.Cu" signal "IN2")
		(12 "In5.Cu" signal "GND2")
		(14 "In6.Cu" signal "IN3")
		(16 "In7.Cu" signal "GND3")
		(18 "In8.Cu" signal "VCC")
		(20 "In9.Cu" signal "VCC1")
		(22 "In10.Cu" signal "GND4")
		(24 "In11.Cu" signal "IN4")
		(26 "In12.Cu" signal "GND5")
		(28 "In13.Cu" signal "IN5")
		(30 "In14.Cu" signal "GND6")
		(32 "In15.Cu" signal "IN6")
		(34 "In16.Cu" signal "GND7")
		(2 "B.Cu" signal "BOTTOM")
		(9 "F.Adhes" user "F.Adhesive")
		(11 "B.Adhes" user "B.Adhesive")
		(13 "F.Paste" user "Package Geometry/Pastemask Top")
		(15 "B.Paste" user "Package Geometry/Pastemask Bottom")
		(5 "F.SilkS" user "Ref Des/Silkscreen Top")
		(7 "B.SilkS" user "Ref Des/Silkscreen Bottom")
		(1 "F.Mask" user "Board Geometry/Soldermask Top")
		(3 "B.Mask" user "Board Geometry/Soldermask Bottom")
		(17 "Dwgs.User" user "User.Drawings")
		(19 "Cmts.User" user "User.Comments")
		(21 "Eco1.User" user "User.Eco1")
		(23 "Eco2.User" user "User.Eco2")
		(25 "Edge.Cuts" user "Board Geometry/Outline")
		(27 "Margin" user)
		(31 "F.CrtYd" user "Package Geometry/Place Bound Top")
		(29 "B.CrtYd" user "Package Geometry/Place Bound Bottom")
		(35 "F.Fab" user "Ref Des/Assembly Top")
		(33 "B.Fab" user "Ref Des/Assembly Bottom")
	)
	(footprint ""
		(layer "B.Cu")
		(at 115.03406 -28.449778 -90)
		(property "Reference" "C6108"
			(at 0 0 90)
			(layer "B.SilkS")
			(hide yes)
			(effects
				(font
					(size 1.27 1.27)
				)
				(justify mirror)
			)
		)
		(property "Value" ""
			(at 0 0 90)
			(layer "B.Fab")
			(effects
				(font
					(size 1.27 1.27)
				)
				(justify mirror)
			)
		)
		(duplicate_pad_numbers_are_jumpers no)
		(fp_line
			(start -0.7874 0.4064)
			(end 0.7874 0.4064)
			(stroke
				(width 0.1524)
				(type default)
			)
			(layer "B.SilkS")
		)
		(fp_line
			(start 0.7874 0.4064)
			(end 0.7874 -0.4064)
			(stroke
				(width 0.1524)
				(type default)
			)
			(layer "B.SilkS")
		)
		(fp_line
			(start -0.7874 -0.4064)
			(end -0.7874 0.4064)
			(stroke
				(width 0.1524)
				(type default)
			)
			(layer "B.SilkS")
		)
		(fp_line
			(start 0.7874 -0.4064)
			(end -0.7874 -0.4064)
			(stroke
				(width 0.1524)
				(type default)
			)
			(layer "B.SilkS")
		)
		(fp_line
			(start -0.67945 0.3048)
			(end -0.120396 0.3048)
			(stroke
				(width 0.1)
				(type default)
			)
			(layer "B.Fab")
		)
		(fp_line
			(start -0.120396 0.3048)
			(end -0.120396 0.2794)
			(stroke
				(width 0.1)
				(type default)
			)
			(layer "B.Fab")
		)
		(fp_line
			(start 0.12065 0.3048)
			(end 0.67945 0.3048)
			(stroke
				(width 0.1)
				(type default)
			)
			(layer "B.Fab")
		)
		(fp_line
			(start 0.67945 0.3048)
			(end 0.67945 -0.305054)
			(stroke
				(width 0.1)
				(type default)
			)
			(layer "B.Fab")
		)
		(fp_line
			(start -0.120396 0.2794)
			(end 0.12065 0.2794)
			(stroke
				(width 0.1)
				(type default)
			)
			(layer "B.Fab")
		)
		(fp_line
			(start 0.12065 0.2794)
			(end 0.12065 0.3048)
			(stroke
				(width 0.1)
				(type default)
			)
			(layer "B.Fab")
		)
		(fp_line
			(start -0.12065 -0.2794)
			(end -0.12065 -0.3048)
			(stroke
				(width 0.1)
				(type default)
			)
			(layer "B.Fab")
		)
		(fp_line
			(start 0.12065 -0.2794)
			(end -0.12065 -0.2794)
			(stroke
				(width 0.1)
				(type default)
			)
			(layer "B.Fab")
		)
		(fp_line
			(start -0.67945 -0.3048)
			(end -0.67945 0.3048)
			(stroke
				(width 0.1)
				(type default)
			)
			(layer "B.Fab")
		)
		(fp_line
			(start -0.12065 -0.3048)
			(end -0.67945 -0.3048)
			(stroke
				(width 0.1)
				(type default)
			)
			(layer "B.Fab")
		)
		(fp_line
			(start 0.12065 -0.305054)
			(end 0.12065 -0.2794)
			(stroke
				(width 0.1)
				(type default)
			)
			(layer "B.Fab")
		)
		(fp_line
			(start 0.67945 -0.305054)
			(end 0.12065 -0.305054)
			(stroke
				(width 0.1)
				(type default)
			)
			(layer "B.Fab")
		)
		(pad "1" smd circle
			(at 0.40005 0 90)
			(size 0 0)
			(layers "B.Cu" "B.Mask" "B.Paste")
			(net "P1V2_CPU0_USB2_DVDD12")
		)
		(pad "2" smd circle
			(at -0.40005 0 90)
			(size 0 0)
			(layers "B.Cu" "B.Mask" "B.Paste")
			(net "GND")
		)
	)
	(footprint ""
		(layer "B.Cu")
		(at 164.33546 -190.821564 180)
		(property "Reference" "R1184"
			(at 0 0 0)
			(layer "B.SilkS")
			(hide yes)
			(effects
				(font
					(size 1.27 1.27)
				)
				(justify mirror)
			)
		)
		(property "Value" ""
			(at 0 0 0)
			(layer "B.Fab")
			(effects
				(font
					(size 1.27 1.27)
				)
				(justify mirror)
			)
		)
		(duplicate_pad_numbers_are_jumpers no)
		(fp_line
			(start 0.7874 0.4064)
			(end 0.7874 -0.4064)
			(stroke
				(width 0.1524)
				(type default)
			)
			(layer "B.SilkS")
		)
		(fp_line
			(start 0.7874 -0.4064)
			(end -0.7874 -0.4064)
			(stroke
				(width 0.1524)
				(type default)
			)
			(layer "B.SilkS")
		)
		(fp_line
			(start -0.7874 0.4064)
			(end 0.7874 0.4064)
			(stroke
				(width 0.1524)
				(type default)
			)
			(layer "B.SilkS")
		)
		(fp_line
			(start -0.7874 -0.4064)
			(end -0.7874 0.4064)
			(stroke
				(width 0.1524)
				(type default)
			)
			(layer "B.SilkS")
		)
		(fp_line
			(start 0.67945 0.3048)
			(end 0.67945 -0.305054)
			(stroke
				(width 0.1)
				(type default)
			)
			(layer "B.Fab")
		)
		(fp_line
			(start 0.67945 -0.305054)
			(end 0.12065 -0.305054)
			(stroke
				(width 0.1)
				(type default)
			)
			(layer "B.Fab")
		)
		(fp_line
			(start 0.12065 0.3048)
			(end 0.67945 0.3048)
			(stroke
				(width 0.1)
				(type default)
			)
			(layer "B.Fab")
		)
		(fp_line
			(start 0.12065 0.2794)
			(end 0.12065 0.3048)
			(stroke
				(width 0.1)
				(type default)
			)
			(layer "B.Fab")
		)
		(fp_line
			(start 0.12065 -0.2794)
			(end -0.12065 -0.2794)
			(stroke
				(width 0.1)
				(type default)
			)
			(layer "B.Fab")
		)
		(fp_line
			(start 0.12065 -0.305054)
			(end 0.12065 -0.2794)
			(stroke
				(width 0.1)
				(type default)
			)
			(layer "B.Fab")
		)
		(fp_line
			(start -0.120396 0.3048)
			(end -0.120396 0.2794)
			(stroke
				(width 0.1)
				(type default)
			)
			(layer "B.Fab")
		)
		(fp_line
			(start -0.120396 0.2794)
			(end 0.12065 0.2794)
			(stroke
				(width 0.1)
				(type default)
			)
			(layer "B.Fab")
		)
		(fp_line
			(start -0.12065 -0.2794)
			(end -0.12065 -0.3048)
			(stroke
				(width 0.1)
				(type default)
			)
			(layer "B.Fab")
		)
		(fp_line
			(start -0.12065 -0.3048)
			(end -0.67945 -0.3048)
			(stroke
				(width 0.1)
				(type default)
			)
			(layer "B.Fab")
		)
		(fp_line
			(start -0.67945 0.3048)
			(end -0.120396 0.3048)
			(stroke
				(width 0.1)
				(type default)
			)
			(layer "B.Fab")
		)
		(fp_line
			(start -0.67945 -0.3048)
			(end -0.67945 0.3048)
			(stroke
				(width 0.1)
				(type default)
			)
			(layer "B.Fab")
		)
		(pad "1" smd circle
			(at 0.40005 0)
			(size 0 0)
			(layers "B.Cu" "B.Mask" "B.Paste")
			(net "PWRGD_CHG_CPU1_DIMM0")
		)
		(pad "2" smd circle
			(at -0.40005 0)
			(size 0 0)
			(layers "B.Cu" "B.Mask" "B.Paste")
			(net "PWRGD_CHGL_CPU1")
		)
	)
)
